# SCM (Grand Teton) — schematic netlist excerpt (pin names and nets, part order shuffled) for the footprints in the layout excerpt that follows; sources: Cadence DE-HDL packaged netlist, KiCad conversion of 12092022_DA0F0TMDCD0_F0T_Management_Board_D_brd_V3_OCP.brd

C501  Q_CAP  0.1UF 25V 10% X7R  pkg 0402  page 31 : A = P3V3_AUX ; B = GND
C271  Q_CAP  0.1UF 25V 10% X7R  pkg 0402  page 12 : A = P2E_GPU_TX_DN ; B = P2E_GPU_TX_C_DN

(kicad_pcb
	(version 20260206)
	(generator "pcbnew")
	(generator_version "10.0")
	(general
		(thickness 1.6)
		(legacy_teardrops no)
	)
	(paper "A4")
	(title_block
		(title "12092022_DA0F0TMDCD0_F0T_Management_Board_D_brd_V3_OCP.brd")
		(comment 1 "Grand Teton / footprints 266-267 of 1440")
	)
	(layers
		(0 "F.Cu" signal "TOP")
		(4 "In1.Cu" signal "GND")
		(6 "In2.Cu" signal "IN1")
		(8 "In3.Cu" signal "GND1")
		(10 "In4.Cu" signal "IN2")
		(12 "In5.Cu" signal "VCC")
		(14 "In6.Cu" signal "VCC1")
		(16 "In7.Cu" signal "IN3")
		(18 "In8.Cu" signal "GND2")
		(20 "In9.Cu" signal "IN4")
		(22 "In10.Cu" signal "GND3")
		(2 "B.Cu" signal "BOTTOM")
		(9 "F.Adhes" user "F.Adhesive")
		(11 "B.Adhes" user "B.Adhesive")
		(13 "F.Paste" user "Package Geometry/Pastemask Top")
		(15 "B.Paste" user "Package Geometry/Pastemask Bottom")
		(5 "F.SilkS" user "Ref Des/Silkscreen Top")
		(7 "B.SilkS" user "Ref Des/Silkscreen Bottom")
		(1 "F.Mask" user "Board Geometry/Soldermask Top")
		(3 "B.Mask" user "Board Geometry/Soldermask Bottom")
		(17 "Dwgs.User" user "User.Drawings")
		(19 "Cmts.User" user "User.Comments")
		(21 "Eco1.User" user "User.Eco1")
		(23 "Eco2.User" user "User.Eco2")
		(25 "Edge.Cuts" user "Board Geometry/Outline")
		(27 "Margin" user)
		(31 "F.CrtYd" user "Package Geometry/Place Bound Top")
		(29 "B.CrtYd" user "Package Geometry/Place Bound Bottom")
		(35 "F.Fab" user "Ref Des/Assembly Top")
		(33 "B.Fab" user "Ref Des/Assembly Bottom")
	)
	(footprint ""
		(layer "F.Cu")
		(at 13.335 -109.347 90)
		(property "Reference" "C271"
			(at 0 0 90)
			(layer "F.SilkS")
			(hide yes)
			(effects
				(font
					(size 1.27 1.27)
				)
			)
		)
		(property "Value" ""
			(at 0 0 90)
			(layer "F.Fab")
			(effects
				(font
					(size 1.27 1.27)
				)
			)
		)
		(duplicate_pad_numbers_are_jumpers no)
		(fp_line
			(start 0.7874 -0.4064)
			(end 0.7874 -0.1016)
			(stroke
				(width 0.1524)
				(type default)
			)
			(layer "F.SilkS")
		)
		(fp_line
			(start -0.7874 -0.4064)
			(end 0.7874 -0.4064)
			(stroke
				(width 0.1524)
				(type default)
			)
			(layer "F.SilkS")
		)
		(fp_line
			(start -0.7874 -0.0254)
			(end -0.7874 -0.4064)
			(stroke
				(width 0.1524)
				(type default)
			)
			(layer "F.SilkS")
		)
		(fp_line
			(start 0.4064 0.4064)
			(end -0.4318 0.4064)
			(stroke
				(width 0.1524)
				(type default)
			)
			(layer "F.SilkS")
		)
		(fp_line
			(start -0.12065 -0.305054)
			(end -0.12065 -0.2794)
			(stroke
				(width 0.1)
				(type default)
			)
			(layer "F.Fab")
		)
		(fp_line
			(start -0.67945 -0.305054)
			(end -0.12065 -0.305054)
			(stroke
				(width 0.1)
				(type default)
			)
			(layer "F.Fab")
		)
		(fp_line
			(start 0.67945 -0.3048)
			(end 0.67945 0.3048)
			(stroke
				(width 0.1)
				(type default)
			)
			(layer "F.Fab")
		)
		(fp_line
			(start 0.12065 -0.3048)
			(end 0.67945 -0.3048)
			(stroke
				(width 0.1)
				(type default)
			)
			(layer "F.Fab")
		)
		(fp_line
			(start 0.12065 -0.2794)
			(end 0.12065 -0.3048)
			(stroke
				(width 0.1)
				(type default)
			)
			(layer "F.Fab")
		)
		(fp_line
			(start -0.12065 -0.2794)
			(end 0.12065 -0.2794)
			(stroke
				(width 0.1)
				(type default)
			)
			(layer "F.Fab")
		)
		(fp_line
			(start 0.120396 0.2794)
			(end -0.12065 0.2794)
			(stroke
				(width 0.1)
				(type default)
			)
			(layer "F.Fab")
		)
		(fp_line
			(start -0.12065 0.2794)
			(end -0.12065 0.3048)
			(stroke
				(width 0.1)
				(type default)
			)
			(layer "F.Fab")
		)
		(fp_line
			(start 0.67945 0.3048)
			(end 0.120396 0.3048)
			(stroke
				(width 0.1)
				(type default)
			)
			(layer "F.Fab")
		)
		(fp_line
			(start 0.120396 0.3048)
			(end 0.120396 0.2794)
			(stroke
				(width 0.1)
				(type default)
			)
			(layer "F.Fab")
		)
		(fp_line
			(start -0.12065 0.3048)
			(end -0.67945 0.3048)
			(stroke
				(width 0.1)
				(type default)
			)
			(layer "F.Fab")
		)
		(fp_line
			(start -0.67945 0.3048)
			(end -0.67945 -0.305054)
			(stroke
				(width 0.1)
				(type default)
			)
			(layer "F.Fab")
		)
		(pad "1" smd circle
			(at -0.40005 0 90)
			(size 0 0)
			(layers "F.Cu" "F.Mask" "F.Paste")
			(net "P2E_GPU_TX_DN")
		)
		(pad "2" smd circle
			(at 0.40005 0 90)
			(size 0 0)
			(layers "F.Cu" "F.Mask" "F.Paste")
			(net "P2E_GPU_TX_C_DN")
		)
	)
	(footprint ""
		(layer "F.Cu")
		(at 16.0782 -65.8622 90)
		(property "Reference" "C501"
			(at 0 0 90)
			(layer "F.SilkS")
			(hide yes)
			(effects
				(font
					(size 1.27 1.27)
				)
			)
		)
		(property "Value" ""
			(at 0 0 90)
			(layer "F.Fab")
			(effects
				(font
					(size 1.27 1.27)
				)
			)
		)
		(duplicate_pad_numbers_are_jumpers no)
		(fp_line
			(start 0.7874 -0.4064)
			(end 0.7874 0.4064)
			(stroke
				(width 0.1524)
				(type default)
			)
			(layer "F.SilkS")
		)
		(fp_line
			(start -0.7874 -0.4064)
			(end 0.7874 -0.4064)
			(stroke
				(width 0.1524)
				(type default)
			)
			(layer "F.SilkS")
		)
		(fp_line
			(start 0.7874 0.4064)
			(end -0.7874 0.4064)
			(stroke
				(width 0.1524)
				(type default)
			)
			(layer "F.SilkS")
		)
		(fp_line
			(start -0.7874 0.4064)
			(end -0.7874 -0.4064)
			(stroke
				(width 0.1524)
				(type default)
			)
			(layer "F.SilkS")
		)
		(fp_line
			(start -0.12065 -0.305054)
			(end -0.12065 -0.2794)
			(stroke
				(width 0.1)
				(type default)
			)
			(layer "F.Fab")
		)
		(fp_line
			(start -0.67945 -0.305054)
			(end -0.12065 -0.305054)
			(stroke
				(width 0.1)
				(type default)
			)
			(layer "F.Fab")
		)
		(fp_line
			(start 0.67945 -0.3048)
			(end 0.67945 0.3048)
			(stroke
				(width 0.1)
				(type default)
			)
			(layer "F.Fab")
		)
		(fp_line
			(start 0.12065 -0.3048)
			(end 0.67945 -0.3048)
			(stroke
				(width 0.1)
				(type default)
			)
			(layer "F.Fab")
		)
		(fp_line
			(start 0.12065 -0.2794)
			(end 0.12065 -0.3048)
			(stroke
				(width 0.1)
				(type default)
			)
			(layer "F.Fab")
		)
		(fp_line
			(start -0.12065 -0.2794)
			(end 0.12065 -0.2794)
			(stroke
				(width 0.1)
				(type default)
			)
			(layer "F.Fab")
		)
		(fp_line
			(start 0.120396 0.2794)
			(end -0.12065 0.2794)
			(stroke
				(width 0.1)
				(type default)
			)
			(layer "F.Fab")
		)
		(fp_line
			(start -0.12065 0.2794)
			(end -0.12065 0.3048)
			(stroke
				(width 0.1)
				(type default)
			)
			(layer "F.Fab")
		)
		(fp_line
			(start 0.67945 0.3048)
			(end 0.120396 0.3048)
			(stroke
				(width 0.1)
				(type default)
			)
			(layer "F.Fab")
		)
		(fp_line
			(start 0.120396 0.3048)
			(end 0.120396 0.2794)
			(stroke
				(width 0.1)
				(type default)
			)
			(layer "F.Fab")
		)
		(fp_line
			(start -0.12065 0.3048)
			(end -0.67945 0.3048)
			(stroke
				(width 0.1)
				(type default)
			)
			(layer "F.Fab")
		)
		(fp_line
			(start -0.67945 0.3048)
			(end -0.67945 -0.305054)
			(stroke
				(width 0.1)
				(type default)
			)
			(layer "F.Fab")
		)
		(pad "1" smd circle
			(at -0.40005 0 90)
			(size 0 0)
			(layers "F.Cu" "F.Mask" "F.Paste")
			(net "P3V3_AUX")
		)
		(pad "2" smd circle
			(at 0.40005 0 90)
			(size 0 0)
			(layers "F.Cu" "F.Mask" "F.Paste")
			(net "GND")
		)
	)
)
